(kicad_pcb
	(version 20221018)
	(generator pcbnew)
	(general
    (thickness 1.7403)
  )
	(paper "A4")
	(title_block
    (title "Data Center RDIMM DDR4 Tester")
    (date "2024-09-30")
    (rev "1.2.4")
		(comment 9 "footprints 166-167 of 690")
	)
	(layers
    (0 "F.Cu" signal)
    (1 "In1.Cu" power)
    (2 "In2.Cu" signal)
    (3 "In3.Cu" power)
    (4 "In4.Cu" power)
    (5 "In5.Cu" signal)
    (6 "In6.Cu" power)
    (7 "In7.Cu" signal)
    (8 "In8.Cu" power)
    (9 "In9.Cu" signal)
    (10 "In10.Cu" power)
    (31 "B.Cu" signal)
    (32 "B.Adhes" user "B.Adhesive")
    (33 "F.Adhes" user "F.Adhesive")
    (34 "B.Paste" user)
    (35 "F.Paste" user)
    (36 "B.SilkS" user "B.Silkscreen")
    (37 "F.SilkS" user "F.Silkscreen")
    (38 "B.Mask" user)
    (39 "F.Mask" user)
    (40 "Dwgs.User" user "User.Drawings")
    (41 "Cmts.User" user "User.Comments")
    (42 "Eco1.User" user "User.Eco1")
    (43 "Eco2.User" user "User.Eco2")
    (44 "Edge.Cuts" user)
    (45 "Margin" user)
    (46 "B.CrtYd" user "B.Courtyard")
    (47 "F.CrtYd" user "F.Courtyard")
    (48 "B.Fab" user)
    (49 "F.Fab" user)
  )
	(footprint "data-center-rdimm-ddr4-tester-footprints:FBGA-24-1_6x8mm_Layout5x5_P1mm" (layer "F.Cu")
    (at 155.496328 80.577157 90)
    (property "Author" "Antmicro")
    (property "License" "Apache-2.0")
    (property "MPN" "S27KL0641DABHI023")
    (property "Manufacturer" "Cypress Semiconductor")
    (property "Sheetfile" "hyperram.kicad_sch")
    (property "Sheetname" "HyperRAM")
    (attr smd)
    (fp_text reference "U11" (at 3.317157 -4.376328 180) (layer "F.SilkS")
        (effects (font (size 0.7 0.7) (thickness 0.15)) (justify left bottom))
    )
    (fp_text value "S27KL0641DABHI023" (at 0.1 5.3 90) (layer "F.Fab") hide
        (effects (font (size 0.7 0.7) (thickness 0.15)) (justify left bottom))
    )
    (fp_text user "${REFERENCE}" (at -3.25 8.359 90) (layer "F.Fab") hide
        (effects (font (size 0.7 0.7) (thickness 0.15)) (justify left bottom))
    )
    (fp_text user "Author: Antmicro" (at -3.25 9.559 90) (layer "F.Fab") hide
        (effects (font (size 0.7 0.7) (thickness 0.15)) (justify left bottom))
    )
    (fp_text user "License: Apache-2.0" (at -3.25 10.759 90) (layer "F.Fab") hide
        (effects (font (size 0.7 0.7) (thickness 0.15)) (justify left bottom))
    )
    (fp_line (start -3.121 -3) (end -3.121 -2.121)
      (stroke (width 0.15) (type solid)) (layer "F.SilkS"))
    (fp_line (start -3.121 4.12) (end -3.121 2.12)
      (stroke (width 0.15) (type solid)) (layer "F.SilkS"))
    (fp_line (start -2 -4.121) (end -3.121 -3)
      (stroke (width 0.15) (type solid)) (layer "F.SilkS"))
    (fp_line (start -1.621 -4.121) (end -2 -4.121)
      (stroke (width 0.15) (type solid)) (layer "F.SilkS"))
    (fp_line (start -1.621 4.12) (end -3.121 4.12)
      (stroke (width 0.15) (type solid)) (layer "F.SilkS"))
    (fp_line (start 1.62 -4.121) (end 3.12 -4.121)
      (stroke (width 0.15) (type solid)) (layer "F.SilkS"))
    (fp_line (start 1.62 -4.121) (end 3.12 -4.121)
      (stroke (width 0.15) (type solid)) (layer "F.SilkS"))
    (fp_line (start 1.62 -4.121) (end 3.12 -4.121)
      (stroke (width 0.15) (type solid)) (layer "F.SilkS"))
    (fp_line (start 1.62 4.12) (end 3.12 4.12)
      (stroke (width 0.15) (type solid)) (layer "F.SilkS"))
    (fp_line (start 3.12 -4.121) (end 3.12 -2.121)
      (stroke (width 0.15) (type solid)) (layer "F.SilkS"))
    (fp_line (start 3.12 -4.121) (end 3.12 -2.121)
      (stroke (width 0.15) (type solid)) (layer "F.SilkS"))
    (fp_line (start 3.12 -4.121) (end 3.12 -2.121)
      (stroke (width 0.15) (type solid)) (layer "F.SilkS"))
    (fp_line (start 3.12 4.12) (end 3.12 2.12)
      (stroke (width 0.15) (type solid)) (layer "F.SilkS"))
    (fp_circle (center -3.6 -3.9) (end -3.5 -3.9)
      (stroke (width 0.15) (type solid)) (fill solid) (layer "F.SilkS"))
    (fp_line (start -3.25 -4.25) (end 3.24 -4.25)
      (stroke (width 0.05) (type solid)) (layer "F.CrtYd"))
    (fp_line (start -3.25 4.24) (end -3.25 -4.25)
      (stroke (width 0.05) (type solid)) (layer "F.CrtYd"))
    (fp_line (start 3.24 -4.25) (end 3.24 4.24)
      (stroke (width 0.05) (type solid)) (layer "F.CrtYd"))
    (fp_line (start 3.24 4.24) (end -3.25 4.24)
      (stroke (width 0.05) (type solid)) (layer "F.CrtYd"))
    (fp_line (start -3 -3) (end -3 3.999)
      (stroke (width 0.15) (type solid)) (layer "F.Fab"))
    (fp_line (start -3 3.999) (end 2.999 3.999)
      (stroke (width 0.15) (type solid)) (layer "F.Fab"))
    (fp_line (start -2 -4) (end -3 -3)
      (stroke (width 0.15) (type solid)) (layer "F.Fab"))
    (fp_line (start 2.999 -4) (end -2 -4)
      (stroke (width 0.15) (type solid)) (layer "F.Fab"))
    (fp_line (start 2.999 3.999) (end 2.999 -4)
      (stroke (width 0.15) (type solid)) (layer "F.Fab"))
    (pad "A2" smd circle (at -1 -2 90) (size 0.4 0.4) (layers "F.Cu" "F.Paste" "F.Mask")
      (net 696 "unconnected-(U11-NC-PadA2)") (pinfunction "NC") (pintype "no_connect"))
    (pad "A3" smd circle (at 0 -2 90) (size 0.4 0.4) (layers "F.Cu" "F.Paste" "F.Mask")
      (net 155 "HR_CS") (pinfunction "~{CS}") (pintype "input"))
    (pad "A4" smd circle (at 0.999 -2 90) (size 0.4 0.4) (layers "F.Cu" "F.Paste" "F.Mask")
      (net 154 "HR_RST") (pinfunction "~{RESET}") (pintype "input"))
    (pad "A5" smd circle (at 1.999 -2 90) (size 0.4 0.4) (layers "F.Cu" "F.Paste" "F.Mask")
      (net 697 "unconnected-(U11-NC-PadA5)") (pinfunction "NC") (pintype "no_connect"))
    (pad "B1" smd circle (at -2 -1 90) (size 0.4 0.4) (layers "F.Cu" "F.Paste" "F.Mask")
      (net 159 "HR_CKN") (pinfunction "CK-") (pintype "input"))
    (pad "B2" smd circle (at -1 -1 90) (size 0.4 0.4) (layers "F.Cu" "F.Paste" "F.Mask")
      (net 164 "HR_CKP") (pinfunction "CK+") (pintype "input"))
    (pad "B3" smd circle (at 0 -1 90) (size 0.4 0.4) (layers "F.Cu" "F.Paste" "F.Mask")
      (net 9 "GND") (pinfunction "VSS") (pintype "power_in"))
    (pad "B4" smd circle (at 0.999 -1 90) (size 0.4 0.4) (layers "F.Cu" "F.Paste" "F.Mask")
      (net 143 "3V3_SYS") (pinfunction "VCC") (pintype "power_in"))
    (pad "B5" smd circle (at 1.999 -1 90) (size 0.4 0.4) (layers "F.Cu" "F.Paste" "F.Mask")
      (net 698 "unconnected-(U11-NC-PadB5)") (pinfunction "NC") (pintype "no_connect"))
    (pad "C1" smd circle (at -2 0 90) (size 0.4 0.4) (layers "F.Cu" "F.Paste" "F.Mask")
      (net 9 "GND") (pinfunction "VSSQ") (pintype "power_in"))
    (pad "C2" smd circle (at -1 0 90) (size 0.4 0.4) (layers "F.Cu" "F.Paste" "F.Mask")
      (net 699 "unconnected-(U11-NC-PadC2)") (pinfunction "NC") (pintype "no_connect"))
    (pad "C3" smd circle (at 0 0 90) (size 0.4 0.4) (layers "F.Cu" "F.Paste" "F.Mask")
      (net 158 "HR_RW") (pinfunction "RWDS") (pintype "bidirectional"))
    (pad "C4" smd circle (at 0.999 0 90) (size 0.4 0.4) (layers "F.Cu" "F.Paste" "F.Mask")
      (net 166 "HR_DQ2") (pinfunction "DQ2") (pintype "bidirectional"))
    (pad "C5" smd circle (at 1.999 0 90) (size 0.4 0.4) (layers "F.Cu" "F.Paste" "F.Mask")
      (net 700 "unconnected-(U11-NC-PadC5)") (pinfunction "NC") (pintype "no_connect"))
    (pad "D1" smd circle (at -2 0.999 90) (size 0.4 0.4) (layers "F.Cu" "F.Paste" "F.Mask")
      (net 143 "3V3_SYS") (pinfunction "VCCQ") (pintype "power_in"))
    (pad "D2" smd circle (at -1 0.999 90) (size 0.4 0.4) (layers "F.Cu" "F.Paste" "F.Mask")
      (net 156 "HR_DQ1") (pinfunction "DQ1") (pintype "bidirectional"))
    (pad "D3" smd circle (at 0 0.999 90) (size 0.4 0.4) (layers "F.Cu" "F.Paste" "F.Mask")
      (net 157 "HR_DQ0") (pinfunction "DQ0") (pintype "bidirectional"))
    (pad "D4" smd circle (at 0.999 0.999 90) (size 0.4 0.4) (layers "F.Cu" "F.Paste" "F.Mask")
      (net 165 "HR_DQ3") (pinfunction "DQ3") (pintype "bidirectional"))
    (pad "D5" smd circle (at 1.999 0.999 90) (size 0.4 0.4) (layers "F.Cu" "F.Paste" "F.Mask")
      (net 161 "HR_DQ4") (pinfunction "DQ4") (pintype "bidirectional"))
    (pad "E1" smd circle (at -2 1.999 90) (size 0.4 0.4) (layers "F.Cu" "F.Paste" "F.Mask")
      (net 162 "HR_DQ7") (pinfunction "DQ7") (pintype "bidirectional"))
    (pad "E2" smd circle (at -1 1.999 90) (size 0.4 0.4) (layers "F.Cu" "F.Paste" "F.Mask")
      (net 163 "HR_DQ6") (pinfunction "DQ6") (pintype "bidirectional"))
    (pad "E3" smd circle (at 0 1.999 90) (size 0.4 0.4) (layers "F.Cu" "F.Paste" "F.Mask")
      (net 160 "HR_DQ5") (pinfunction "DQ5") (pintype "bidirectional"))
    (pad "E4" smd circle (at 0.999 1.999 90) (size 0.4 0.4) (layers "F.Cu" "F.Paste" "F.Mask")
      (net 143 "3V3_SYS") (pinfunction "VCCQ") (pintype "passive"))
    (pad "E5" smd circle (at 1.999 1.999 90) (size 0.4 0.4) (layers "F.Cu" "F.Paste" "F.Mask")
      (net 9 "GND") (pinfunction "VSSQ") (pintype "passive"))
  )
	(footprint "data-center-rdimm-ddr4-tester-footprints:R_0402_1005Metric" (layer "F.Cu")
    (at 153.7202 75.502 -90)
    (descr "Resistor SMD 0402")
    (tags "resistor SMD 0402")
    (property "Author" "Antmicro")
    (property "License" "Apache-2.0")
    (property "MPN" "CR0402-FX-1002GLF")
    (property "Manufacturer" "Bourns")
    (property "Sheetfile" "hyperram.kicad_sch")
    (property "Sheetname" "HyperRAM")
    (property "Tolerance" "1%")
    (property "Val" "10k")
    (property "ki_description" "10k resistor in 0402 package with 1% tolerance")
    (attr smd)
    (fp_text reference "R56" (at -0.832 -0.3574 -90) (layer "F.SilkS")
        (effects (font (size 0.7 0.7) (thickness 0.15)) (justify left bottom))
    )
    (fp_text value "R_10k_0402" (at 0 1.4 -90) (layer "F.Fab") hide
        (effects (font (size 0.7 0.7) (thickness 0.15)) (justify left bottom))
    )
    (fp_text user "${REFERENCE}" (at -0.95 3.168 -90) (layer "F.Fab") hide
        (effects (font (size 0.7 0.7) (thickness 0.15)) (justify left bottom))
    )
    (fp_text user "License: Apache-2.0" (at -0.95 5.169 -90) (layer "F.Fab") hide
        (effects (font (size 0.7 0.7) (thickness 0.15)) (justify left bottom))
    )
    (fp_text user "Author: Antmicro" (at -0.95 4.169 -90) (layer "F.Fab") hide
        (effects (font (size 0.7 0.7) (thickness 0.15)) (justify left bottom))
    )
    (fp_rect (start -0.93 -0.47) (end 0.93 0.47)
      (stroke (width 0.05) (type solid)) (fill none) (layer "F.CrtYd"))
    (fp_rect (start -0.5 -0.25) (end 0.5 0.25)
      (stroke (width 0.15) (type solid)) (fill none) (layer "F.Fab"))
    (pad "1" smd roundrect (at -0.485 0 270) (size 0.59 0.64) (layers "F.Cu" "F.Paste" "F.Mask") (roundrect_rratio 0.25)
      (net 143 "3V3_SYS") (pintype "passive"))
    (pad "2" smd roundrect (at 0.485 0 270) (size 0.59 0.64) (layers "F.Cu" "F.Paste" "F.Mask") (roundrect_rratio 0.25)
      (net 154 "HR_RST") (pintype "passive"))
  )
)
